# S9S_MB_2U (Grand Teton) — schematic netlist excerpt (pin names and nets, part order shuffled) for the footprints in the layout excerpt that follows; sources: Cadence DE-HDL packaged netlist, KiCad conversion of 03242023_DA0F0TMBIJ0_F0T_Motherboard_J_brd_V01_OCP.brd

R332  Q_RES  10K 1% CHIP  pkg 0402LF  page 127 : A = PD_PIROM_CPU0_ADDR2 ; B = GND
R3524  Q_RES  54.9K 1% CHIP  pkg 0402LF  page 234 : A = P3V3_AUX ; B = SMB_1_BMC_GPU_BUF_R_SDA

(kicad_pcb
	(version 20260206)
	(generator "pcbnew")
	(generator_version "10.0")
	(general
		(thickness 1.6)
		(legacy_teardrops no)
	)
	(paper "A4")
	(title_block
		(title "03242023_DA0F0TMBIJ0_F0T_Motherboard_J_brd_V01_OCP.brd")
		(comment 1 "Grand Teton / footprints 3613-3614 of 6105")
	)
	(layers
		(0 "F.Cu" signal "TOP")
		(4 "In1.Cu" signal "GND")
		(6 "In2.Cu" signal "IN1")
		(8 "In3.Cu" signal "GND1")
		(10 "In4.Cu" signal "IN2")
		(12 "In5.Cu" signal "GND2")
		(14 "In6.Cu" signal "IN3")
		(16 "In7.Cu" signal "GND3")
		(18 "In8.Cu" signal "VCC")
		(20 "In9.Cu" signal "VCC1")
		(22 "In10.Cu" signal "GND4")
		(24 "In11.Cu" signal "IN4")
		(26 "In12.Cu" signal "GND5")
		(28 "In13.Cu" signal "IN5")
		(30 "In14.Cu" signal "GND6")
		(32 "In15.Cu" signal "IN6")
		(34 "In16.Cu" signal "GND7")
		(2 "B.Cu" signal "BOTTOM")
		(9 "F.Adhes" user "F.Adhesive")
		(11 "B.Adhes" user "B.Adhesive")
		(13 "F.Paste" user "Package Geometry/Pastemask Top")
		(15 "B.Paste" user "Package Geometry/Pastemask Bottom")
		(5 "F.SilkS" user "Ref Des/Silkscreen Top")
		(7 "B.SilkS" user "Ref Des/Silkscreen Bottom")
		(1 "F.Mask" user "Board Geometry/Soldermask Top")
		(3 "B.Mask" user "Board Geometry/Soldermask Bottom")
		(17 "Dwgs.User" user "User.Drawings")
		(19 "Cmts.User" user "User.Comments")
		(21 "Eco1.User" user "User.Eco1")
		(23 "Eco2.User" user "User.Eco2")
		(25 "Edge.Cuts" user "Board Geometry/Outline")
		(27 "Margin" user)
		(31 "F.CrtYd" user "Package Geometry/Place Bound Top")
		(29 "B.CrtYd" user "Package Geometry/Place Bound Bottom")
		(35 "F.Fab" user "Ref Des/Assembly Top")
		(33 "B.Fab" user "Ref Des/Assembly Bottom")
	)
	(footprint ""
		(layer "F.Cu")
		(at 52.480972 -435.360318 180)
		(property "Reference" "R3524"
			(at 0 0 180)
			(layer "F.SilkS")
			(hide yes)
			(effects
				(font
					(size 1.27 1.27)
				)
			)
		)
		(property "Value" ""
			(at 0 0 180)
			(layer "F.Fab")
			(effects
				(font
					(size 1.27 1.27)
				)
			)
		)
		(duplicate_pad_numbers_are_jumpers no)
		(fp_line
			(start 0.7874 0.4064)
			(end -0.7874 0.4064)
			(stroke
				(width 0.1524)
				(type default)
			)
			(layer "F.SilkS")
		)
		(fp_line
			(start 0.7874 -0.4064)
			(end 0.7874 0.4064)
			(stroke
				(width 0.1524)
				(type default)
			)
			(layer "F.SilkS")
		)
		(fp_line
			(start -0.7874 0.4064)
			(end -0.7874 -0.4064)
			(stroke
				(width 0.1524)
				(type default)
			)
			(layer "F.SilkS")
		)
		(fp_line
			(start -0.7874 -0.4064)
			(end 0.7874 -0.4064)
			(stroke
				(width 0.1524)
				(type default)
			)
			(layer "F.SilkS")
		)
		(fp_line
			(start 0.67945 0.3048)
			(end 0.120396 0.3048)
			(stroke
				(width 0.1)
				(type default)
			)
			(layer "F.Fab")
		)
		(fp_line
			(start 0.67945 -0.3048)
			(end 0.67945 0.3048)
			(stroke
				(width 0.1)
				(type default)
			)
			(layer "F.Fab")
		)
		(fp_line
			(start 0.12065 -0.2794)
			(end 0.12065 -0.3048)
			(stroke
				(width 0.1)
				(type default)
			)
			(layer "F.Fab")
		)
		(fp_line
			(start 0.12065 -0.3048)
			(end 0.67945 -0.3048)
			(stroke
				(width 0.1)
				(type default)
			)
			(layer "F.Fab")
		)
		(fp_line
			(start 0.120396 0.3048)
			(end 0.120396 0.2794)
			(stroke
				(width 0.1)
				(type default)
			)
			(layer "F.Fab")
		)
		(fp_line
			(start 0.120396 0.2794)
			(end -0.12065 0.2794)
			(stroke
				(width 0.1)
				(type default)
			)
			(layer "F.Fab")
		)
		(fp_line
			(start -0.12065 0.3048)
			(end -0.67945 0.3048)
			(stroke
				(width 0.1)
				(type default)
			)
			(layer "F.Fab")
		)
		(fp_line
			(start -0.12065 0.2794)
			(end -0.12065 0.3048)
			(stroke
				(width 0.1)
				(type default)
			)
			(layer "F.Fab")
		)
		(fp_line
			(start -0.12065 -0.2794)
			(end 0.12065 -0.2794)
			(stroke
				(width 0.1)
				(type default)
			)
			(layer "F.Fab")
		)
		(fp_line
			(start -0.12065 -0.305054)
			(end -0.12065 -0.2794)
			(stroke
				(width 0.1)
				(type default)
			)
			(layer "F.Fab")
		)
		(fp_line
			(start -0.67945 0.3048)
			(end -0.67945 -0.305054)
			(stroke
				(width 0.1)
				(type default)
			)
			(layer "F.Fab")
		)
		(fp_line
			(start -0.67945 -0.305054)
			(end -0.12065 -0.305054)
			(stroke
				(width 0.1)
				(type default)
			)
			(layer "F.Fab")
		)
		(pad "1" smd circle
			(at -0.40005 0 180)
			(size 0 0)
			(layers "F.Cu" "F.Mask" "F.Paste")
			(net "P3V3_AUX")
		)
		(pad "2" smd circle
			(at 0.40005 0 180)
			(size 0 0)
			(layers "F.Cu" "F.Mask" "F.Paste")
			(net "SMB_1_BMC_GPU_BUF_R_SDA")
		)
	)
	(footprint ""
		(layer "F.Cu")
		(at 406.124664 -360.722926)
		(property "Reference" "R332"
			(at 0 0 0)
			(layer "F.SilkS")
			(hide yes)
			(effects
				(font
					(size 1.27 1.27)
				)
			)
		)
		(property "Value" ""
			(at 0 0 0)
			(layer "F.Fab")
			(effects
				(font
					(size 1.27 1.27)
				)
			)
		)
		(duplicate_pad_numbers_are_jumpers no)
		(fp_line
			(start -0.7874 -0.4064)
			(end 0.7874 -0.4064)
			(stroke
				(width 0.1524)
				(type default)
			)
			(layer "F.SilkS")
		)
		(fp_line
			(start -0.7874 0.4064)
			(end -0.7874 -0.4064)
			(stroke
				(width 0.1524)
				(type default)
			)
			(layer "F.SilkS")
		)
		(fp_line
			(start 0.7874 -0.4064)
			(end 0.7874 0.4064)
			(stroke
				(width 0.1524)
				(type default)
			)
			(layer "F.SilkS")
		)
		(fp_line
			(start 0.7874 0.4064)
			(end -0.7874 0.4064)
			(stroke
				(width 0.1524)
				(type default)
			)
			(layer "F.SilkS")
		)
		(fp_line
			(start -0.67945 -0.305054)
			(end -0.12065 -0.305054)
			(stroke
				(width 0.1)
				(type default)
			)
			(layer "F.Fab")
		)
		(fp_line
			(start -0.67945 0.3048)
			(end -0.67945 -0.305054)
			(stroke
				(width 0.1)
				(type default)
			)
			(layer "F.Fab")
		)
		(fp_line
			(start -0.12065 -0.305054)
			(end -0.12065 -0.2794)
			(stroke
				(width 0.1)
				(type default)
			)
			(layer "F.Fab")
		)
		(fp_line
			(start -0.12065 -0.2794)
			(end 0.12065 -0.2794)
			(stroke
				(width 0.1)
				(type default)
			)
			(layer "F.Fab")
		)
		(fp_line
			(start -0.12065 0.2794)
			(end -0.12065 0.3048)
			(stroke
				(width 0.1)
				(type default)
			)
			(layer "F.Fab")
		)
		(fp_line
			(start -0.12065 0.3048)
			(end -0.67945 0.3048)
			(stroke
				(width 0.1)
				(type default)
			)
			(layer "F.Fab")
		)
		(fp_line
			(start 0.120396 0.2794)
			(end -0.12065 0.2794)
			(stroke
				(width 0.1)
				(type default)
			)
			(layer "F.Fab")
		)
		(fp_line
			(start 0.120396 0.3048)
			(end 0.120396 0.2794)
			(stroke
				(width 0.1)
				(type default)
			)
			(layer "F.Fab")
		)
		(fp_line
			(start 0.12065 -0.3048)
			(end 0.67945 -0.3048)
			(stroke
				(width 0.1)
				(type default)
			)
			(layer "F.Fab")
		)
		(fp_line
			(start 0.12065 -0.2794)
			(end 0.12065 -0.3048)
			(stroke
				(width 0.1)
				(type default)
			)
			(layer "F.Fab")
		)
		(fp_line
			(start 0.67945 -0.3048)
			(end 0.67945 0.3048)
			(stroke
				(width 0.1)
				(type default)
			)
			(layer "F.Fab")
		)
		(fp_line
			(start 0.67945 0.3048)
			(end 0.120396 0.3048)
			(stroke
				(width 0.1)
				(type default)
			)
			(layer "F.Fab")
		)
		(pad "1" smd circle
			(at -0.40005 0)
			(size 0 0)
			(layers "F.Cu" "F.Mask" "F.Paste")
			(net "PD_PIROM_CPU0_ADDR2")
		)
		(pad "2" smd circle
			(at 0.40005 0)
			(size 0 0)
			(layers "F.Cu" "F.Mask" "F.Paste")
			(net "GND")
		)
	)
)
